# S9S_MB_2U (Grand Teton) — schematic netlist excerpt (pin names and nets, part order shuffled) for the footprints in the layout excerpt that follows; sources: Cadence DE-HDL packaged netlist, KiCad conversion of 03242023_DA0F0TMBIJ0_F0T_Motherboard_J_brd_V01_OCP.brd

R4663  Q_RES  0 5% CHIP  pkg 0402LF  page 167 : A = P2E_MB_BMC_RX_DP<0> ; B = P2E_MB_BMC_RX_R1_DP<0>
R3520  Q_RES  4.7K 5% CHIP  pkg 0402LF  page 238 : A = P3V3_OCP_V3_2 ; B = SMB_OCP_V3_2_3V3AUX_BUF_SDA
C861  Q_CAP_DIFFBUS  DIFF BUS_0.22UF 6.3V 20% X6S  pkg C0201  page 174 : \1\ = P5E_CPU0_PE1_TX_C_DP<4> ; \2\ = P5E_CPU0_PE1_TX_DP<4>

(kicad_pcb
	(version 20260206)
	(generator "pcbnew")
	(generator_version "10.0")
	(general
		(thickness 1.6)
		(legacy_teardrops no)
	)
	(paper "A4")
	(title_block
		(title "03242023_DA0F0TMBIJ0_F0T_Motherboard_J_brd_V01_OCP.brd")
		(comment 1 "Grand Teton / footprints 1821-1823 of 6105")
	)
	(layers
		(0 "F.Cu" signal "TOP")
		(4 "In1.Cu" signal "GND")
		(6 "In2.Cu" signal "IN1")
		(8 "In3.Cu" signal "GND1")
		(10 "In4.Cu" signal "IN2")
		(12 "In5.Cu" signal "GND2")
		(14 "In6.Cu" signal "IN3")
		(16 "In7.Cu" signal "GND3")
		(18 "In8.Cu" signal "VCC")
		(20 "In9.Cu" signal "VCC1")
		(22 "In10.Cu" signal "GND4")
		(24 "In11.Cu" signal "IN4")
		(26 "In12.Cu" signal "GND5")
		(28 "In13.Cu" signal "IN5")
		(30 "In14.Cu" signal "GND6")
		(32 "In15.Cu" signal "IN6")
		(34 "In16.Cu" signal "GND7")
		(2 "B.Cu" signal "BOTTOM")
		(9 "F.Adhes" user "F.Adhesive")
		(11 "B.Adhes" user "B.Adhesive")
		(13 "F.Paste" user "Package Geometry/Pastemask Top")
		(15 "B.Paste" user "Package Geometry/Pastemask Bottom")
		(5 "F.SilkS" user "Ref Des/Silkscreen Top")
		(7 "B.SilkS" user "Ref Des/Silkscreen Bottom")
		(1 "F.Mask" user "Board Geometry/Soldermask Top")
		(3 "B.Mask" user "Board Geometry/Soldermask Bottom")
		(17 "Dwgs.User" user "User.Drawings")
		(19 "Cmts.User" user "User.Comments")
		(21 "Eco1.User" user "User.Eco1")
		(23 "Eco2.User" user "User.Eco2")
		(25 "Edge.Cuts" user "Board Geometry/Outline")
		(27 "Margin" user)
		(31 "F.CrtYd" user "Package Geometry/Place Bound Top")
		(29 "B.CrtYd" user "Package Geometry/Place Bound Bottom")
		(35 "F.Fab" user "Ref Des/Assembly Top")
		(33 "B.Fab" user "Ref Des/Assembly Bottom")
	)
	(footprint ""
		(layer "F.Cu")
		(at 98.31705 -32.636714)
		(property "Reference" "R3520"
			(at 0 0 0)
			(layer "F.SilkS")
			(hide yes)
			(effects
				(font
					(size 1.27 1.27)
				)
			)
		)
		(property "Value" ""
			(at 0 0 0)
			(layer "F.Fab")
			(effects
				(font
					(size 1.27 1.27)
				)
			)
		)
		(duplicate_pad_numbers_are_jumpers no)
		(fp_line
			(start -0.7874 -0.4064)
			(end 0.7874 -0.4064)
			(stroke
				(width 0.1524)
				(type default)
			)
			(layer "F.SilkS")
		)
		(fp_line
			(start -0.7874 0.4064)
			(end -0.7874 -0.4064)
			(stroke
				(width 0.1524)
				(type default)
			)
			(layer "F.SilkS")
		)
		(fp_line
			(start 0.7874 -0.4064)
			(end 0.7874 0.4064)
			(stroke
				(width 0.1524)
				(type default)
			)
			(layer "F.SilkS")
		)
		(fp_line
			(start 0.7874 0.4064)
			(end -0.7874 0.4064)
			(stroke
				(width 0.1524)
				(type default)
			)
			(layer "F.SilkS")
		)
		(fp_line
			(start -0.67945 -0.305054)
			(end -0.12065 -0.305054)
			(stroke
				(width 0.1)
				(type default)
			)
			(layer "F.Fab")
		)
		(fp_line
			(start -0.67945 0.3048)
			(end -0.67945 -0.305054)
			(stroke
				(width 0.1)
				(type default)
			)
			(layer "F.Fab")
		)
		(fp_line
			(start -0.12065 -0.305054)
			(end -0.12065 -0.2794)
			(stroke
				(width 0.1)
				(type default)
			)
			(layer "F.Fab")
		)
		(fp_line
			(start -0.12065 -0.2794)
			(end 0.12065 -0.2794)
			(stroke
				(width 0.1)
				(type default)
			)
			(layer "F.Fab")
		)
		(fp_line
			(start -0.12065 0.2794)
			(end -0.12065 0.3048)
			(stroke
				(width 0.1)
				(type default)
			)
			(layer "F.Fab")
		)
		(fp_line
			(start -0.12065 0.3048)
			(end -0.67945 0.3048)
			(stroke
				(width 0.1)
				(type default)
			)
			(layer "F.Fab")
		)
		(fp_line
			(start 0.120396 0.2794)
			(end -0.12065 0.2794)
			(stroke
				(width 0.1)
				(type default)
			)
			(layer "F.Fab")
		)
		(fp_line
			(start 0.120396 0.3048)
			(end 0.120396 0.2794)
			(stroke
				(width 0.1)
				(type default)
			)
			(layer "F.Fab")
		)
		(fp_line
			(start 0.12065 -0.3048)
			(end 0.67945 -0.3048)
			(stroke
				(width 0.1)
				(type default)
			)
			(layer "F.Fab")
		)
		(fp_line
			(start 0.12065 -0.2794)
			(end 0.12065 -0.3048)
			(stroke
				(width 0.1)
				(type default)
			)
			(layer "F.Fab")
		)
		(fp_line
			(start 0.67945 -0.3048)
			(end 0.67945 0.3048)
			(stroke
				(width 0.1)
				(type default)
			)
			(layer "F.Fab")
		)
		(fp_line
			(start 0.67945 0.3048)
			(end 0.120396 0.3048)
			(stroke
				(width 0.1)
				(type default)
			)
			(layer "F.Fab")
		)
		(pad "1" smd circle
			(at -0.40005 0)
			(size 0 0)
			(layers "F.Cu" "F.Mask" "F.Paste")
			(net "P3V3_OCP_V3_2")
		)
		(pad "2" smd circle
			(at 0.40005 0)
			(size 0 0)
			(layers "F.Cu" "F.Mask" "F.Paste")
			(net "SMB_OCP_V3_2_3V3AUX_BUF_SDA")
		)
	)
	(footprint ""
		(layer "F.Cu")
		(at 421.9702 -17.612614 90)
		(property "Reference" "C861"
			(at 0 0 90)
			(layer "F.SilkS")
			(hide yes)
			(effects
				(font
					(size 1.27 1.27)
				)
			)
		)
		(property "Value" ""
			(at 0 0 90)
			(layer "F.Fab")
			(effects
				(font
					(size 1.27 1.27)
				)
			)
		)
		(duplicate_pad_numbers_are_jumpers no)
		(fp_line
			(start 0.299974 -0.150114)
			(end 0.299974 0.150114)
			(stroke
				(width 0.1)
				(type default)
			)
			(layer "F.Fab")
		)
		(fp_line
			(start -0.299974 -0.150114)
			(end 0.299974 -0.150114)
			(stroke
				(width 0.1)
				(type default)
			)
			(layer "F.Fab")
		)
		(fp_line
			(start 0.299974 0.150114)
			(end -0.299974 0.150114)
			(stroke
				(width 0.1)
				(type default)
			)
			(layer "F.Fab")
		)
		(fp_line
			(start -0.299974 0.150114)
			(end -0.299974 -0.150114)
			(stroke
				(width 0.1)
				(type default)
			)
			(layer "F.Fab")
		)
		(pad "1" smd rect
			(at -0.2667 0 90)
			(size 0.3048 0.381)
			(layers "F.Cu" "F.Mask" "F.Paste")
			(net "P5E_CPU0_PE1_TX_C_DP<4>")
		)
		(pad "2" smd rect
			(at 0.2667 0 90)
			(size 0.3048 0.381)
			(layers "F.Cu" "F.Mask" "F.Paste")
			(net "P5E_CPU0_PE1_TX_DP<4>")
		)
	)
	(footprint ""
		(layer "F.Cu")
		(at 25.9715 -396.888462 -90)
		(property "Reference" "R4663"
			(at 0 0 270)
			(layer "F.SilkS")
			(hide yes)
			(effects
				(font
					(size 1.27 1.27)
				)
			)
		)
		(property "Value" ""
			(at 0 0 270)
			(layer "F.Fab")
			(effects
				(font
					(size 1.27 1.27)
				)
			)
		)
		(duplicate_pad_numbers_are_jumpers no)
		(fp_line
			(start -0.7874 0.4064)
			(end -0.7874 -0.4064)
			(stroke
				(width 0.1524)
				(type default)
			)
			(layer "F.SilkS")
		)
		(fp_line
			(start 0.7874 0.4064)
			(end 0.003302 0.4064)
			(stroke
				(width 0.1524)
				(type default)
			)
			(layer "F.SilkS")
		)
		(fp_line
			(start -0.7874 -0.4064)
			(end 0.7874 -0.4064)
			(stroke
				(width 0.1524)
				(type default)
			)
			(layer "F.SilkS")
		)
		(fp_line
			(start -0.67945 0.3048)
			(end -0.67945 -0.305054)
			(stroke
				(width 0.1)
				(type default)
			)
			(layer "F.Fab")
		)
		(fp_line
			(start -0.12065 0.3048)
			(end -0.67945 0.3048)
			(stroke
				(width 0.1)
				(type default)
			)
			(layer "F.Fab")
		)
		(fp_line
			(start 0.120396 0.3048)
			(end 0.120396 0.2794)
			(stroke
				(width 0.1)
				(type default)
			)
			(layer "F.Fab")
		)
		(fp_line
			(start 0.67945 0.3048)
			(end 0.120396 0.3048)
			(stroke
				(width 0.1)
				(type default)
			)
			(layer "F.Fab")
		)
		(fp_line
			(start -0.12065 0.2794)
			(end -0.12065 0.3048)
			(stroke
				(width 0.1)
				(type default)
			)
			(layer "F.Fab")
		)
		(fp_line
			(start 0.120396 0.2794)
			(end -0.12065 0.2794)
			(stroke
				(width 0.1)
				(type default)
			)
			(layer "F.Fab")
		)
		(fp_line
			(start -0.12065 -0.2794)
			(end 0.12065 -0.2794)
			(stroke
				(width 0.1)
				(type default)
			)
			(layer "F.Fab")
		)
		(fp_line
			(start 0.12065 -0.2794)
			(end 0.12065 -0.3048)
			(stroke
				(width 0.1)
				(type default)
			)
			(layer "F.Fab")
		)
		(fp_line
			(start 0.12065 -0.3048)
			(end 0.67945 -0.3048)
			(stroke
				(width 0.1)
				(type default)
			)
			(layer "F.Fab")
		)
		(fp_line
			(start 0.67945 -0.3048)
			(end 0.67945 0.3048)
			(stroke
				(width 0.1)
				(type default)
			)
			(layer "F.Fab")
		)
		(fp_line
			(start -0.67945 -0.305054)
			(end -0.12065 -0.305054)
			(stroke
				(width 0.1)
				(type default)
			)
			(layer "F.Fab")
		)
		(fp_line
			(start -0.12065 -0.305054)
			(end -0.12065 -0.2794)
			(stroke
				(width 0.1)
				(type default)
			)
			(layer "F.Fab")
		)
		(pad "1" smd rect
			(at -0.40005 0 90)
			(size 0.4572 0.508)
			(layers "F.Cu" "F.Mask" "F.Paste")
			(net "P2E_MB_BMC_RX_DP<0>")
		)
		(pad "2" smd rect
			(at 0.40005 0 90)
			(size 0.4572 0.508)
			(layers "F.Cu" "F.Mask" "F.Paste")
			(net "P2E_MB_BMC_RX_R1_DP<0>")
		)
	)
)
